FILE_TYPE = CONNECTIVITY;
{Allegro Design Entry HDL 16.6-p007 (v16-6-112F) 10/10/2012}
"PAGE_NUMBER" = 94;
0"NC";
1"PVPP_ABC\g";
2"GND\g";
3"GND\g";
4"P3V3\g";
5"GND\g";
6"GND\g";
7"P3V3\g";
8"GND\g";
9"GND\g";
10"GND\g";
11"P3V3\g";
12"GND\g";
13"P3V3\g";
14"GND\g";
15"P3V3_STBY\g";
16"GND\g";
17"GND\g";
18"PVPP_ABC\g";
19"H_CPU1_MEMKLM_MEMHOT_G_N";
20"H_CPU1_MEMGHJ_MEMHOT_G_N";
21"H_CPU1_MEMGHJ_MEMHOT";
22"H_CPU1_MEMKLM_MEMHOT";
23"IRQ_PVDDQ_GHJ_VRHOT_LVT3_N";
24"IRQ_PVDDQ_KLM_VRHOT_LVT3_N";
25"H_CPU0_MEMDEF_MEMHOT_G_N";
26"H_CPU0_MEMDEF_MEMHOT";
27"IRQ_PVDDQ_DEF_VRHOT_LVT3_N";
28"IRQ_PVDDQ_ABC_VRHOT_LVT3_N";
29"FM_MEM_THERM_EVENT_LVT3_N";
30"FM_DIMM_EVENT_FET";
31"H_CPU0_MEMABC_MEMHOT_G_N";
32"H_CPU0_MEMABC_MEMHOT";
33"FM_DIMM_EVENT_COD_N";
%"RES"
"2","(-300,3650)","2","mstr_discrete","I100";
;
CDS_SEC"1"
LOCATION"R4U2"
PART_NUMBER"G21796-112"
VALUE"2.21K"
TOLERANCE"1%"
PACK_TYPE"0402"
WATTAGE"1/16W"
MATERIAL"CHIP"
SEC_TYPE"0402"
BOM_COST"PROC_SIDEBAND"
CDS_LIB"mstr_discrete"
SEC"1"
CDS_LOCATION"R4U2"
ROOM"PROC_SIDEBAND";
"A"
$PN"1"18;
"B"
$PN"2"33;
%"FET_N_DUAL"
"5","(1400,3950)","0","mstr_discrete","I102";
;
CDS_SEC"2"
LOCATION"Q4U1"
PART_NUMBER"E40049-001"
VALUE"NTJD4001N"
MATERIAL"FET"
PACK_TYPE"SMLF"
SEC_TYPE"SMLF"
CDS_LIB"mstr_discrete"
BOM_COST"PROC_SIDEBAND"
SEC"2"
CDS_LOCATION"Q4U1"
ROOM"PROC_SIDEBAND";
"GATE <SIZE -1..0>"
$PN"5"30;
"SOURCE <SIZE-1..0>"
$PN"4"16;
"DRAIN <SIZE -1..0>"
$PN"3"29;
%"PVPP_ABC"
"1","(175,4300)","0","mstr_symbols","I103";
;
VOLTAGE"2.5V"
BOM_COST"PVPP_KLM_VR"
CDS_LIB"mstr_symbols"
ROOM"PVPP_KLM_VR"
BODY_TYPE"PLUMBING"
HDL_POWER"PVPP_ABC";
"G\NAC"1;
%"RES"
"2","(750,3575)","0","mstr_discrete","I104";
;
CDS_SEC"1"
TOLERANCE"5%"
MATERIAL"CHIP"
WATTAGE"1/16W"
PART_NUMBER"G21497-023"
PACK_TYPE"0402"
VALUE"33.0K"
LOCATION"R4U4"
CDS_LIB"mstr_discrete"
SEC_TYPE"0402"
SEC"1"
CDS_LOCATION"R4U4";
"A"
$PN"1"30;
"B"
$PN"2"2;
%"GND"
"1","(750,3225)","0","mstr_symbols","I105";
;
VOLTAGE"0"
CDS_LIB"mstr_symbols"
SIZE"1B"
BODY_TYPE"PLUMBING"
HDL_POWER"GND";
"A\NAC"2;
%"GND"
"1","(-1425,1750)","0","mstr_symbols","I47";
;
VOLTAGE"0"
SIZE"1B"
CDS_LIB"mstr_symbols"
ROOM"PROCHOT_MEMHOT_ISO"
BODY_TYPE"PLUMBING"
HDL_POWER"GND";
"A\NAC"3;
%"FET_N_DUAL"
"5","(-2150,1925)","0","mstr_discrete","I49";
;
CDS_SEC"1"
LOCATION"Q3U1"
PART_NUMBER"E40049-001"
MATERIAL"FET"
VALUE"NTJD4001N"
PACK_TYPE"SMLF"
CDS_LIB"mstr_discrete"
SEC_TYPE"SMLF"
SEC"1"
CDS_LOCATION"Q3U1"
ROOM"PROC_SIDEBAND";
"GATE <SIZE -1..0>"
$PN"2"28;
"SOURCE <SIZE-1..0>"
$PN"1"5;
"DRAIN <SIZE -1..0>"
$PN"6"32;
%"P3V3"
"1","(-2150,2575)","0","mstr_symbols","I50";
;
VOLTAGE"+3.3"
CDS_LIB"mstr_symbols"
SIZE"1B"
ROOM"PROC_SIDEBAND"
BODY_TYPE"PLUMBING"
HDL_POWER"P3V3";
"G\NAC"4;
%"RES"
"2","(-2150,2375)","2","mstr_discrete","I51";
;
LOCATION"R7G7"
VALUE"4.75K"
TOLERANCE"1%"
PACK_TYPE"0402"
MATERIAL"CHIP"
WATTAGE"1/16W"
PART_NUMBER"G21796-072"
CDS_LIB"mstr_discrete"
BOM_COST"PROC_SIDEBAND"
CDS_SEC"1"
$SEC"1"
CDS_LOCATION"R7G7"
ROOM"PROC_SIDEBAND";
"A"
$PN"1"4;
"B"
$PN"2"32;
%"GND"
"1","(-2150,1650)","0","mstr_symbols","I56";
;
VOLTAGE"0"
SIZE"1B"
CDS_LIB"mstr_symbols"
ROOM"PROCHOT_MEMHOT_ISO"
BODY_TYPE"PLUMBING"
HDL_POWER"GND";
"A\NAC"5;
%"FET_N_DUAL"
"5","(-2150,825)","0","mstr_discrete","I60";
;
CDS_SEC"1"
LOCATION"Q7E1"
PART_NUMBER"E40049-001"
VALUE"NTJD4001N"
MATERIAL"FET"
PACK_TYPE"SMLF"
CDS_LIB"mstr_discrete"
SEC_TYPE"SMLF"
SEC"1"
CDS_LOCATION"Q7E1"
ROOM"PROC_SIDEBAND";
"GATE <SIZE -1..0>"
$PN"2"27;
"SOURCE <SIZE-1..0>"
$PN"1"8;
"DRAIN <SIZE -1..0>"
$PN"6"26;
%"GND"
"1","(-1425,650)","0","mstr_symbols","I63";
;
VOLTAGE"0"
SIZE"1B"
CDS_LIB"mstr_symbols"
ROOM"PROCHOT_MEMHOT_ISO"
BODY_TYPE"PLUMBING"
HDL_POWER"GND";
"A\NAC"6;
%"FET_N_DUAL"
"5","(-1425,950)","0","mstr_discrete","I64";
;
CDS_SEC"2"
LOCATION"Q7E1"
PART_NUMBER"E40049-001"
VALUE"NTJD4001N"
MATERIAL"FET"
PACK_TYPE"SMLF"
CDS_LIB"mstr_discrete"
SEC_TYPE"SMLF"
SEC"2"
CDS_LOCATION"Q7E1"
ROOM"PROC_SIDEBAND";
"GATE <SIZE -1..0>"
$PN"5"26;
"SOURCE <SIZE-1..0>"
$PN"4"6;
"DRAIN <SIZE -1..0>"
$PN"3"25;
%"P3V3"
"1","(-2150,1475)","0","mstr_symbols","I65";
;
VOLTAGE"+3.3"
SIZE"1B"
CDS_LIB"mstr_symbols"
ROOM"PROCHOT_MEMHOT_ISO"
BODY_TYPE"PLUMBING"
HDL_POWER"P3V3";
"G\NAC"7;
%"RES"
"2","(-2150,1275)","2","mstr_discrete","I66";
;
LOCATION"R3R4"
PART_NUMBER"G21796-072"
VALUE"4.75K"
TOLERANCE"1%"
PACK_TYPE"0402"
MATERIAL"CHIP"
WATTAGE"1/16W"
CDS_LIB"mstr_discrete"
BOM_COST"PROC_SIDEBAND"
CDS_SEC"1"
$SEC"1"
CDS_LOCATION"R3R4"
ROOM"PROC_SIDEBAND";
"A"
$PN"1"7;
"B"
$PN"2"26;
%"GND"
"1","(-2150,550)","0","mstr_symbols","I67";
;
VOLTAGE"0"
SIZE"1B"
CDS_LIB"mstr_symbols"
ROOM"PROCHOT_MEMHOT_ISO"
BODY_TYPE"PLUMBING"
HDL_POWER"GND";
"A\NAC"8;
%"FET_N_DUAL"
"5","(1175,1975)","0","mstr_discrete","I69";
;
CDS_SEC"1"
LOCATION"Q7E2"
PART_NUMBER"E40049-001"
VALUE"NTJD4001N"
MATERIAL"FET"
PACK_TYPE"SMLF"
SEC_TYPE"SMLF"
CDS_LIB"mstr_discrete"
SEC"1"
CDS_LOCATION"Q7E2"
ROOM"PROC_SIDEBAND";
"GATE <SIZE -1..0>"
$PN"2"23;
"SOURCE <SIZE-1..0>"
$PN"1"12;
"DRAIN <SIZE -1..0>"
$PN"6"21;
%"GND"
"1","(1900,1800)","0","mstr_symbols","I74";
;
VOLTAGE"0"
CDS_LIB"mstr_symbols"
SIZE"1B"
ROOM"PROCHOT_MEMHOT_ISO"
BODY_TYPE"PLUMBING"
HDL_POWER"GND";
"A\NAC"9;
%"FET_N_DUAL"
"5","(1900,2100)","0","mstr_discrete","I75";
;
CDS_SEC"2"
LOCATION"Q7E2"
MATERIAL"FET"
PART_NUMBER"E40049-001"
VALUE"NTJD4001N"
PACK_TYPE"SMLF"
SEC_TYPE"SMLF"
CDS_LIB"mstr_discrete"
SEC"2"
CDS_LOCATION"Q7E2"
ROOM"PROC_SIDEBAND";
"GATE <SIZE -1..0>"
$PN"5"21;
"SOURCE <SIZE-1..0>"
$PN"4"9;
"DRAIN <SIZE -1..0>"
$PN"3"20;
%"GND"
"1","(1900,700)","0","mstr_symbols","I76";
;
VOLTAGE"0"
CDS_LIB"mstr_symbols"
SIZE"1B"
ROOM"PROCHOT_MEMHOT_ISO"
BODY_TYPE"PLUMBING"
HDL_POWER"GND";
"A\NAC"10;
%"FET_N_DUAL"
"5","(1900,1000)","0","mstr_discrete","I77";
;
CDS_SEC"2"
LOCATION"Q4B1"
VALUE"NTJD4001N"
MATERIAL"FET"
PART_NUMBER"E40049-001"
PACK_TYPE"SMLF"
SEC_TYPE"SMLF"
CDS_LIB"mstr_discrete"
SEC"2"
CDS_LOCATION"Q4B1"
ROOM"PROC_SIDEBAND";
"GATE <SIZE -1..0>"
$PN"5"22;
"SOURCE <SIZE-1..0>"
$PN"4"10;
"DRAIN <SIZE -1..0>"
$PN"3"19;
%"P3V3"
"1","(1175,2625)","0","mstr_symbols","I78";
;
VOLTAGE"+3.3"
CDS_LIB"mstr_symbols"
SIZE"1B"
ROOM"PROCHOT_MEMHOT_ISO"
BODY_TYPE"PLUMBING"
HDL_POWER"P3V3";
"G\NAC"11;
%"RES"
"2","(1175,2425)","2","mstr_discrete","I79";
;
LOCATION"R3R10"
VALUE"4.75K"
TOLERANCE"1%"
PART_NUMBER"G21796-072"
WATTAGE"1/16W"
MATERIAL"CHIP"
PACK_TYPE"0402"
BOM_COST"PROC_SIDEBAND"
CDS_LIB"mstr_discrete"
CDS_SEC"1"
$SEC"1"
CDS_LOCATION"R3R10"
ROOM"PROC_SIDEBAND";
"A"
$PN"1"11;
"B"
$PN"2"21;
%"GND"
"1","(1175,1700)","0","mstr_symbols","I80";
;
VOLTAGE"0"
CDS_LIB"mstr_symbols"
SIZE"1B"
ROOM"PROCHOT_MEMHOT_ISO"
BODY_TYPE"PLUMBING"
HDL_POWER"GND";
"A\NAC"12;
%"P3V3"
"1","(1175,1525)","0","mstr_symbols","I81";
;
VOLTAGE"+3.3"
CDS_LIB"mstr_symbols"
SIZE"1B"
ROOM"PROCHOT_MEMHOT_ISO"
BODY_TYPE"PLUMBING"
HDL_POWER"P3V3";
"G\NAC"13;
%"RES"
"2","(1175,1325)","2","mstr_discrete","I82";
;
LOCATION"R6M4"
PART_NUMBER"G21796-072"
VALUE"4.75K"
TOLERANCE"1%"
PACK_TYPE"0402"
MATERIAL"CHIP"
WATTAGE"1/16W"
BOM_COST"PROC_SIDEBAND"
CDS_LIB"mstr_discrete"
CDS_SEC"1"
$SEC"1"
CDS_LOCATION"R6M4"
ROOM"PROC_SIDEBAND";
"A"
$PN"1"13;
"B"
$PN"2"22;
%"GND"
"1","(1175,600)","0","mstr_symbols","I83";
;
VOLTAGE"0"
CDS_LIB"mstr_symbols"
SIZE"1B"
ROOM"PROCHOT_MEMHOT_ISO"
BODY_TYPE"PLUMBING"
HDL_POWER"GND";
"A\NAC"14;
%"FET_N_DUAL"
"5","(1175,875)","0","mstr_discrete","I84";
;
CDS_SEC"1"
MATERIAL"FET"
LOCATION"Q4B1"
VALUE"NTJD4001N"
PART_NUMBER"E40049-001"
PACK_TYPE"SMLF"
SEC_TYPE"SMLF"
CDS_LIB"mstr_discrete"
SEC"1"
CDS_LOCATION"Q4B1"
ROOM"PROC_SIDEBAND";
"GATE <SIZE -1..0>"
$PN"2"24;
"SOURCE <SIZE-1..0>"
$PN"1"14;
"DRAIN <SIZE -1..0>"
$PN"6"22;
%"FET_N_DUAL"
"5","(-1425,2050)","0","mstr_discrete","I89";
;
CDS_SEC"2"
LOCATION"Q3U1"
VALUE"NTJD4001N"
MATERIAL"FET"
PART_NUMBER"E40049-001"
PACK_TYPE"SMLF"
SEC_TYPE"SMLF"
CDS_LIB"mstr_discrete"
SEC"2"
CDS_LOCATION"Q3U1"
ROOM"PROC_SIDEBAND";
"GATE <SIZE -1..0>"
$PN"5"32;
"SOURCE <SIZE-1..0>"
$PN"4"3;
"DRAIN <SIZE -1..0>"
$PN"3"31;
%"RES"
"2","(1400,4450)","2","mstr_discrete","I91";
;
CDS_SEC"1"
LOCATION"R4U1"
VALUE"4.75K"
TOLERANCE"1%"
WATTAGE"1/16W"
PART_NUMBER"G21796-072"
MATERIAL"CHIP"
PACK_TYPE"0402"
CDS_LOCATION"R4U1"
SEC"1"
SEC_TYPE"0402"
CDS_LIB"mstr_discrete"
BOM_COST"PROC_SIDEBAND"
ROOM"PROC_SIDEBAND";
"A"
$PN"1"15;
"B"
$PN"2"29;
%"P3V3_STBY"
"1","(1400,4700)","0","mstr_symbols","I92";
;
VOLTAGE"3.3V"
SIZE"1B"
CDS_LIB"mstr_symbols"
BODY_TYPE"PLUMBING"
HDL_POWER"P3V3_STBY";
"G\NAC"15;
%"RES"
"2","(175,4075)","2","mstr_discrete","I94";
;
CDS_SEC"1"
LOCATION"R4U3"
PART_NUMBER"G21796-072"
VALUE"4.75K"
TOLERANCE"1%"
PACK_TYPE"0402"
WATTAGE"1/16W"
MATERIAL"CHIP"
SEC_TYPE"0402"
BOM_COST"PROC_SIDEBAND"
CDS_LIB"mstr_discrete"
SEC"1"
CDS_LOCATION"R4U3"
ROOM"PROC_SIDEBAND";
"A"
$PN"1"1;
"B"
$PN"2"30;
%"GND"
"1","(1400,3550)","0","mstr_symbols","I95";
;
VOLTAGE"0"
CDS_LIB"mstr_symbols"
SIZE"1B"
BOM_COST"DEBUG"
ROOM"SYSTEM_DEBUG_LEDS"
BODY_TYPE"PLUMBING"
HDL_POWER"GND";
"A\NAC"16;
%"GND"
"1","(175,3225)","0","mstr_symbols","I97";
;
VOLTAGE"0"
SIZE"1B"
CDS_LIB"mstr_symbols"
BODY_TYPE"PLUMBING"
HDL_POWER"GND";
"A\NAC"17;
%"FET_N_DUAL"
"5","(175,3525)","0","mstr_discrete","I98";
;
CDS_SEC"1"
VALUE"NTJD4001N"
MATERIAL"FET"
LOCATION"Q4U1"
PART_NUMBER"E40049-001"
PACK_TYPE"SMLF"
CDS_LIB"mstr_discrete"
SEC_TYPE"SMLF"
BOM_COST"PROC_SIDEBAND"
SEC"1"
CDS_LOCATION"Q4U1"
ROOM"PROC_SIDEBAND";
"GATE <SIZE -1..0>"
$PN"2"33;
"SOURCE <SIZE-1..0>"
$PN"1"17;
"DRAIN <SIZE -1..0>"
$PN"6"30;
%"PVPP_ABC"
"1","(-300,4050)","0","mstr_symbols","I99";
;
VOLTAGE"2.5V"
BOM_COST"PVPP_KLM_VR"
CDS_LIB"mstr_symbols"
ROOM"PVPP_KLM_VR"
BODY_TYPE"PLUMBING"
HDL_POWER"PVPP_ABC";
"G\NAC"18;
END.
